FILE_TYPE = CONNECTIVITY;
{Allegro Design Entry HDL 17.2-2016 S081 (4005846) 1/11/2022}
"PAGE_NUMBER" = 183;
0"NC";
1"P3V3_AUX\g";
2"P3V3_E1S_0\g";
3"P3V3_AUX\g";
4"P1V8_PCH_AUX\g";
5"P3V3_E1S_0\g";
6"P3V3_AUX\g";
7"P1V8_PCH_AUX\g";
8"GND\g";
9"GND\g";
10"GND\g";
11"GND\g";
12"GND\g"VOLTAGE"0";
13"GND\g";
14"SMB_E1S_3V3AUX_ISO_SCL_R"CDS_PHYS_NET_NAME"SMB_SENSOR_M2_P0_3V3AUX_SCL";
15"SMB_PCIE_E1S_ISO_EN_R"CDS_PHYS_NET_NAME"SMB_PCIE_M2_1_EN";
16"SMB_SENSOR_E1S_3V3AUX_SDA"CDS_PHYS_NET_NAME"SMB_SENSOR_M2_P0_3V3AUX_SCL";
17"SMB_SENSOR_E1S_3V3AUX_SCL"CDS_PHYS_NET_NAME"SMB_SENSOR_M2_P0_3V3AUX_SDA";
18"SMB_E1S_3V3AUX_ISO_SDA_R"CDS_PHYS_NET_NAME"SMB_SENSOR_M2_P0_3V3AUX_SDA";
19"SMB_PCIE_M2_0_EN"CDS_PHYS_NET_NAME"SMB_SENSOR_M2_P0_3V3AUX_SDA";
20"SMB_M2_P0_1V8AUX_SCL_R"CDS_PHYS_NET_NAME"SMB_SENSOR_M2_P0_3V3AUX_SDA";
21"SMB_M2_P0_1V8AUX_SDA_R"CDS_PHYS_NET_NAME"SMB_SENSOR_M2_P0_3V3AUX_SCL";
22"SMB_SENSOR_M2_P0_3V3AUX_SCL"CDS_PHYS_NET_NAME"SMB_SENSOR_M2_P0_3V3AUX_SDA";
23"SMB_SENSOR_M2_P0_3V3AUX_SDA"CDS_PHYS_NET_NAME"SMB_SENSOR_M2_P0_3V3AUX_SCL";
24"SMB_E1S_3V3AUX_ISO_SCL"CDS_PHYS_NET_NAME"SMB_SENSOR_M2_P0_3V3AUX_SCL";
25"SMB_E1S_3V3AUX_ISO_SDA"CDS_PHYS_NET_NAME"SMB_SENSOR_M2_P0_3V3AUX_SDA";
26"SMB_PCIE_E1S_ISO_EN"CDS_PHYS_NET_NAME"PWRGD_P1V8_PCH_AUX";
27"PWRGD_P1V8_PCH_AUX"CDS_PHYS_NET_NAME"SMB_SENSOR_M2_P0_3V3AUX_SDA";
28"FM_PCH_SATA_RAID_KEY"CDS_PHYS_NET_NAME"FM_PCH_SATA_RAID_KEY";
29"SMB_M2_P0_1V8AUX_SDA"CDS_PHYS_NET_NAME"SMB_SENSOR_M2_P0_3V3AUX_SCL";
30"SMB_M2_P0_1V8AUX_SCL"CDS_PHYS_NET_NAME"SMB_SENSOR_M2_P0_3V3AUX_SDA";
%"PCA9306DP1"
"1","(725,3400)","2","pure_quanta","I27";
;
PART_NUMBER"AL009306K04"
VALUE"PCA9306DP1"
PART_TYPE"SMLF"
MATERIAL"IC"
$LOCATION"U98"
CDS_LMAN_SYM_OUTLINE"-200,175,200,-175"
NEEDS_NO_SIZE"TRUE"
CDS_LIB"pure_quanta"
CDS_LOCATION"U98"
$SEC"1"
CDS_SEC"1";
"GND"
$PN"1"12;
"EN"
$PN"8"19;
"VREF2"
$PN"7"19;
"SCL2"
$PN"6"22;
"SDA2"
$PN"5"23;
"SDA1"
$PN"4"21;
"SCL1"
$PN"3"20;
"VREF1"
$PN"2"4;
%"Q_CAP"
"1","(1400,3800)","0","pure_quanta","I28";
;
PART_NUMBER"CH4104K1B00"
VALUE"0.1UF"
MATERIAL"X7R"
VOLTAGE"25V"
TOLERANCE"10%"
PACK_TYPE"0402"
$LOCATION"C1323"
CDS_LIB"pure_quanta"
CDS_LOCATION"C1323"
$SEC"1"
CDS_SEC"1";
"B"
$PN"2"13;
"A"
$PN"1"4;
%"UNIVERSAL_POWER"
"1","(1225,4100)","0","logical_power","I29";
;
HDL_POWER"P1V8_PCH_AUX"
CDS_LIB"logical_power";
"A"4;
%"UNIVERSAL_POWER"
"1","(-2100,225)","0","logical_power","I3";
;
HDL_POWER"P3V3_AUX"
CDS_LIB"logical_power";
"A"1;
%"UNIVERSAL_GND"
"1","(1400,3575)","0","logical_power","I30";
;
HDL_POWER"GND"
CDS_LIB"logical_power";
"A"13;
%"UNIVERSAL_GND"
"1","(350,3150)","0","logical_power","I38";
;
CDS_LIB"logical_power"
HDL_POWER"GND";
"A"12;
%"Q_RES"
"2","(2250,3775)","0","pure_quanta","I43";
;
PART_NUMBER"CS24702JB10"
VALUE"4.7K"
TOLERANCE"5%"
PACK_TYPE"0402LF"
MATERIAL"CHIP"
WATTAGE"1/16W"
$LOCATION"R1702"
CDS_LIB"pure_quanta"
CDS_LOCATION"R1702"
$SEC"1"
CDS_SEC"1";
"A"
$PN"1"7;
"B"
$PN"2"21;
%"Q_RES"
"2","(2500,3775)","0","pure_quanta","I45";
;
PART_NUMBER"CS24702JB10"
PACK_TYPE"0402LF"
MATERIAL"CHIP"
TOLERANCE"5%"
VALUE"4.7K"
WATTAGE"1/16W"
$LOCATION"R1703"
CDS_LIB"pure_quanta"
CDS_LOCATION"R1703"
$SEC"1"
CDS_SEC"1";
"A"
$PN"1"7;
"B"
$PN"2"20;
%"UNIVERSAL_POWER"
"1","(2250,4100)","0","logical_power","I47";
;
HDL_POWER"P1V8_PCH_AUX"
CDS_LIB"logical_power";
"A"7;
%"Q_RES"
"2","(-2100,-200)","0","pure_quanta","I5";
;
PART_NUMBER"CS22212FB06"
WATTAGE"1/16W"
PACK_TYPE"0402LF"
VALUE"2.21K"
TOLERANCE"1%"
MATERIAL"EMPTY"
$LOCATION"R1271"
CDS_LIB"pure_quanta"
CDS_LOCATION"R1271"
$SEC"1"
CDS_SEC"1";
"A"
$PN"1"1;
"B"
$PN"2"28;
%"UNIVERSAL_POWER"
"1","(0,4125)","0","logical_power","I51";
;
HDL_POWER"P3V3_AUX"
CDS_LIB"logical_power";
"A"6;
%"Q_CAP"
"1","(-425,3775)","2","pure_quanta","I52";
;
PART_NUMBER"CH4104K1B00"
TOLERANCE"10%"
VALUE"0.1UF"
PACK_TYPE"0402"
VOLTAGE"25V"
MATERIAL"X7R"
$LOCATION"C1305"
CDS_LIB"pure_quanta"
CDS_LOCATION"C1305"
$SEC"1"
CDS_SEC"1";
"B"
$PN"2"11;
"A"
$PN"1"6;
%"UNIVERSAL_GND"
"1","(-425,3575)","0","logical_power","I53";
;
HDL_POWER"GND"
CDS_LIB"logical_power";
"A"11;
%"Q_RES"
"1","(2800,3425)","0","pure_quanta","I65";
;
PART_NUMBER"CS03322FB03"
MATERIAL"CHIP"
VALUE"33.2"
WATTAGE"1/16W"
PACK_TYPE"0402LF"
TOLERANCE"1%"
$LOCATION"R2410"
CDS_LIB"pure_quanta"
CDS_LOCATION"R2410"
$SEC"1"
CDS_SEC"1";
"B"
$PN"2"29;
"A"
$PN"1"21;
%"Q_RES"
"1","(2800,3375)","0","pure_quanta","I66";
;
PART_NUMBER"CS03322FB03"
VALUE"33.2"
MATERIAL"CHIP"
TOLERANCE"1%"
$LOCATION"R2411"
CDS_LIB"pure_quanta"
PACK_TYPE"0402LF"
WATTAGE"1/16W"
CDS_LOCATION"R2411"
$SEC"1"
CDS_SEC"1";
"B"
$PN"2"30;
"A"
$PN"1"20;
%"Q_RES"
"1","(2300,3100)","0","pure_quanta","I70";
;
PART_NUMBER"CS42002FB05"
MATERIAL"EMPTY"
TOLERANCE"1%"
VALUE"200K"
WATTAGE"1/16W"
PACK_TYPE"0402LF"
$LOCATION"R2476"
CDS_LIB"pure_quanta"
CDS_LOCATION"R2476"
$SEC"1"
CDS_SEC"1";
"B"
$PN"2"27;
"A"
$PN"1"19;
%"Q_RES"
"2","(0,3750)","0","pure_quanta","I72";
;
PART_NUMBER"CS42002FB05"
TOLERANCE"1%"
PACK_TYPE"0402LF"
MATERIAL"CHIP"
WATTAGE"1/16W"
VALUE"200K"
$LOCATION"R1700"
CDS_LIB"pure_quanta"
CDS_LOCATION"R1700"
$SEC"1"
CDS_SEC"1";
"A"
$PN"1"6;
"B"
$PN"2"19;
%"Q_RES"
"1","(2700,1225)","0","pure_quanta","I76";
;
PART_NUMBER"CS03322FB03"
WATTAGE"1/16W"
PACK_TYPE"0402LF"
VALUE"33.2"
MATERIAL"CHIP"
TOLERANCE"1%"
$LOCATION"R3533"
CDS_LIB"pure_quanta"
CDS_LOCATION"R3533"
$SEC"1"
CDS_SEC"1";
"B"
$PN"2"24;
"A"
$PN"1"14;
%"Q_RES"
"1","(2700,1125)","0","pure_quanta","I77";
;
PART_NUMBER"CS03322FB03"
TOLERANCE"1%"
VALUE"33.2"
MATERIAL"CHIP"
$LOCATION"R3534"
WATTAGE"1/16W"
PACK_TYPE"0402LF"
CDS_LIB"pure_quanta"
CDS_LOCATION"R3534"
$SEC"1"
CDS_SEC"1";
"B"
$PN"2"25;
"A"
$PN"1"18;
%"Q_RES"
"2","(2375,1575)","0","pure_quanta","I78";
;
PART_NUMBER"CS24702JB10"
VALUE"4.7K"
TOLERANCE"5%"
PACK_TYPE"0402LF"
WATTAGE"1/16W"
MATERIAL"CHIP"
$LOCATION"R3532"
CDS_LIB"pure_quanta"
CDS_LOCATION"R3532"
$SEC"1"
CDS_SEC"1";
"A"
$PN"1"5;
"B"
$PN"2"18;
%"Q_RES"
"2","(2125,1575)","0","pure_quanta","I80";
;
PART_NUMBER"CS24702JB10"
VALUE"4.7K"
MATERIAL"CHIP"
PACK_TYPE"0402LF"
TOLERANCE"5%"
WATTAGE"1/16W"
$LOCATION"R3530"
CDS_LIB"pure_quanta"
CDS_LOCATION"R3530"
$SEC"1"
CDS_SEC"1";
"A"
$PN"1"5;
"B"
$PN"2"14;
%"Q_CAP"
"1","(1600,1650)","0","pure_quanta","I82";
;
PART_NUMBER"CH4104K1B00"
PACK_TYPE"0402"
VOLTAGE"25V"
MATERIAL"X7R"
TOLERANCE"10%"
VALUE"0.1UF"
$LOCATION"C1998"
CDS_LIB"pure_quanta"
CDS_LOCATION"C1998"
$SEC"1"
CDS_SEC"1";
"B"
$PN"2"10;
"A"
$PN"1"2;
%"UNIVERSAL_GND"
"1","(1600,1425)","0","logical_power","I84";
;
CDS_LIB"logical_power"
HDL_POWER"GND";
"A"10;
%"UNIVERSAL_POWER"
"1","(75,1975)","0","logical_power","I87";
;
HDL_POWER"P3V3_AUX"
CDS_LIB"logical_power";
"A"3;
%"Q_CAP"
"1","(-350,1625)","2","pure_quanta","I89";
;
PART_NUMBER"CH4104K1B00"
PACK_TYPE"0402"
VOLTAGE"25V"
VALUE"0.1UF"
TOLERANCE"10%"
MATERIAL"X7R"
$LOCATION"C1997"
CDS_LIB"pure_quanta"
CDS_LOCATION"C1997"
$SEC"1"
CDS_SEC"1";
"B"
$PN"2"8;
"A"
$PN"1"3;
%"UNIVERSAL_GND"
"1","(-350,1425)","0","logical_power","I90";
;
CDS_LIB"logical_power"
HDL_POWER"GND";
"A"8;
%"PCA9617ADP"
"1","(850,1175)","2","pure_quanta","I93";
;
PART_NUMBER"AL009617K02"
MATERIAL"IC"
PART_TYPE"SMLF"
VALUE"PCA9617ADP"
$LOCATION"U279"
NEEDS_NO_SIZE"TRUE"
CDS_LMAN_SYM_OUTLINE"-275,300,275,-300"
CDS_LIB"pure_quanta"
CDS_LOCATION"U279"
$SEC"1"
CDS_SEC"1";
"GND"
$PN"4"9;
"SCLB"
$PN"7"17;
"SDAB"
$PN"6"16;
"SDAA"
$PN"3"18;
"SCLA"
$PN"2"14;
"VCCB"
$PN"8"3;
"VCCA"
$PN"1"2;
"EN"
$PN"5"15;
%"UNIVERSAL_GND"
"1","(1450,850)","0","logical_power","I95";
;
CDS_LIB"logical_power"
HDL_POWER"GND";
"A"9;
%"Q_RES"
"1","(-1500,975)","0","pure_quanta","I96";
;
PART_NUMBER"CS42002FB05"
MATERIAL"EMPTY"
TOLERANCE"1%"
VALUE"200K"
WATTAGE"1/16W"
PACK_TYPE"0402LF"
$LOCATION"R3531"
CDS_LIB"pure_quanta"
CDS_LOCATION"R3531"
$SEC"1"
CDS_SEC"1";
"B"
$PN"2"15;
"A"
$PN"1"26;
%"UNIVERSAL_POWER"
"1","(1425,1950)","0","logical_power","I97";
;
HDL_POWER"P3V3_E1S_0"
CDS_LIB"logical_power";
"A"2;
%"UNIVERSAL_POWER"
"1","(2125,1900)","0","logical_power","I98";
;
HDL_POWER"P3V3_E1S_0"
CDS_LIB"logical_power";
"A"5;
%"Q_RES"
"2","(-25,1600)","0","pure_quanta","I99";
;
PART_NUMBER"CS31002FB08"
TOLERANCE"1%"
MATERIAL"CHIP"
PACK_TYPE"0402LF"
VALUE"10K"
WATTAGE"1/16W"
LOCATION"R3529"
CDS_LIB"pure_quanta"
$SEC"1"
CDS_SEC"1";
"A"
$PN"1"3;
"B"
$PN"2"15;
END.
